(kicad_pcb
	(version 20260206)
	(generator "pcbnew")
	(generator_version "10.0")
	(general
		(thickness 1.6)
		(legacy_teardrops no)
	)
	(paper "A4")
	(title_block
		(title "03242023_DA0F0TMBIJ0_F0T_Motherboard_J_brd_V01_OCP.brd")
		(comment 1 "Grand Teton / footprints 5504-5510 of 6105")
	)
	(layers
		(0 "F.Cu" signal "TOP")
		(4 "In1.Cu" signal "GND")
		(6 "In2.Cu" signal "IN1")
		(8 "In3.Cu" signal "GND1")
		(10 "In4.Cu" signal "IN2")
		(12 "In5.Cu" signal "GND2")
		(14 "In6.Cu" signal "IN3")
		(16 "In7.Cu" signal "GND3")
		(18 "In8.Cu" signal "VCC")
		(20 "In9.Cu" signal "VCC1")
		(22 "In10.Cu" signal "GND4")
		(24 "In11.Cu" signal "IN4")
		(26 "In12.Cu" signal "GND5")
		(28 "In13.Cu" signal "IN5")
		(30 "In14.Cu" signal "GND6")
		(32 "In15.Cu" signal "IN6")
		(34 "In16.Cu" signal "GND7")
		(2 "B.Cu" signal "BOTTOM")
		(9 "F.Adhes" user "F.Adhesive")
		(11 "B.Adhes" user "B.Adhesive")
		(13 "F.Paste" user "Package Geometry/Pastemask Top")
		(15 "B.Paste" user "Package Geometry/Pastemask Bottom")
		(5 "F.SilkS" user "Ref Des/Silkscreen Top")
		(7 "B.SilkS" user "Ref Des/Silkscreen Bottom")
		(1 "F.Mask" user "Board Geometry/Soldermask Top")
		(3 "B.Mask" user "Board Geometry/Soldermask Bottom")
		(17 "Dwgs.User" user "User.Drawings")
		(19 "Cmts.User" user "User.Comments")
		(21 "Eco1.User" user "User.Eco1")
		(23 "Eco2.User" user "User.Eco2")
		(25 "Edge.Cuts" user "Board Geometry/Outline")
		(27 "Margin" user)
		(31 "F.CrtYd" user "Package Geometry/Place Bound Top")
		(29 "B.CrtYd" user "Package Geometry/Place Bound Bottom")
		(35 "F.Fab" user "Ref Des/Assembly Top")
		(33 "B.Fab" user "Ref Des/Assembly Bottom")
	)
	(footprint ""
		(layer "B.Cu")
		(at 401.832318 -229.12451 -90)
		(property "Reference" "R10"
			(at 0 0 90)
			(layer "B.SilkS")
			(hide yes)
			(effects
				(font
					(size 1.27 1.27)
				)
				(justify mirror)
			)
		)
		(property "Value" ""
			(at 0 0 90)
			(layer "B.Fab")
			(effects
				(font
					(size 1.27 1.27)
				)
				(justify mirror)
			)
		)
		(duplicate_pad_numbers_are_jumpers no)
		(fp_line
			(start -0.7874 0.4064)
			(end 0.7874 0.4064)
			(stroke
				(width 0.1524)
				(type default)
			)
			(layer "B.SilkS")
		)
		(fp_line
			(start 0.7874 0.4064)
			(end 0.7874 -0.4064)
			(stroke
				(width 0.1524)
				(type default)
			)
			(layer "B.SilkS")
		)
		(fp_line
			(start -0.7874 -0.4064)
			(end -0.7874 0.4064)
			(stroke
				(width 0.1524)
				(type default)
			)
			(layer "B.SilkS")
		)
		(fp_line
			(start 0.7874 -0.4064)
			(end -0.7874 -0.4064)
			(stroke
				(width 0.1524)
				(type default)
			)
			(layer "B.SilkS")
		)
		(fp_line
			(start -0.67945 0.3048)
			(end -0.120396 0.3048)
			(stroke
				(width 0.1)
				(type default)
			)
			(layer "B.Fab")
		)
		(fp_line
			(start -0.120396 0.3048)
			(end -0.120396 0.2794)
			(stroke
				(width 0.1)
				(type default)
			)
			(layer "B.Fab")
		)
		(fp_line
			(start 0.12065 0.3048)
			(end 0.67945 0.3048)
			(stroke
				(width 0.1)
				(type default)
			)
			(layer "B.Fab")
		)
		(fp_line
			(start 0.67945 0.3048)
			(end 0.67945 -0.305054)
			(stroke
				(width 0.1)
				(type default)
			)
			(layer "B.Fab")
		)
		(fp_line
			(start -0.120396 0.2794)
			(end 0.12065 0.2794)
			(stroke
				(width 0.1)
				(type default)
			)
			(layer "B.Fab")
		)
		(fp_line
			(start 0.12065 0.2794)
			(end 0.12065 0.3048)
			(stroke
				(width 0.1)
				(type default)
			)
			(layer "B.Fab")
		)
		(fp_line
			(start -0.12065 -0.2794)
			(end -0.12065 -0.3048)
			(stroke
				(width 0.1)
				(type default)
			)
			(layer "B.Fab")
		)
		(fp_line
			(start 0.12065 -0.2794)
			(end -0.12065 -0.2794)
			(stroke
				(width 0.1)
				(type default)
			)
			(layer "B.Fab")
		)
		(fp_line
			(start -0.67945 -0.3048)
			(end -0.67945 0.3048)
			(stroke
				(width 0.1)
				(type default)
			)
			(layer "B.Fab")
		)
		(fp_line
			(start -0.12065 -0.3048)
			(end -0.67945 -0.3048)
			(stroke
				(width 0.1)
				(type default)
			)
			(layer "B.Fab")
		)
		(fp_line
			(start 0.12065 -0.305054)
			(end 0.12065 -0.2794)
			(stroke
				(width 0.1)
				(type default)
			)
			(layer "B.Fab")
		)
		(fp_line
			(start 0.67945 -0.305054)
			(end 0.12065 -0.305054)
			(stroke
				(width 0.1)
				(type default)
			)
			(layer "B.Fab")
		)
		(pad "1" smd circle
			(at 0.40005 0 90)
			(size 0 0)
			(layers "B.Cu" "B.Mask" "B.Paste")
			(net "H_CPU0_PMSYNC_PCH_R")
		)
		(pad "2" smd circle
			(at -0.40005 0 90)
			(size 0 0)
			(layers "B.Cu" "B.Mask" "B.Paste")
			(net "H_CPU0_PMSYNC_PCH")
		)
	)
	(footprint ""
		(layer "B.Cu")
		(at 235.30052 -249.220228 -90)
		(property "Reference" "C2258"
			(at 0 0 90)
			(layer "B.SilkS")
			(hide yes)
			(effects
				(font
					(size 1.27 1.27)
				)
				(justify mirror)
			)
		)
		(property "Value" ""
			(at 0 0 90)
			(layer "B.Fab")
			(effects
				(font
					(size 1.27 1.27)
				)
				(justify mirror)
			)
		)
		(duplicate_pad_numbers_are_jumpers no)
		(fp_line
			(start -0.7874 0.4064)
			(end 0.7874 0.4064)
			(stroke
				(width 0.1524)
				(type default)
			)
			(layer "B.SilkS")
		)
		(fp_line
			(start 0.7874 0.4064)
			(end 0.7874 -0.4064)
			(stroke
				(width 0.1524)
				(type default)
			)
			(layer "B.SilkS")
		)
		(fp_line
			(start -0.7874 -0.4064)
			(end -0.7874 0.4064)
			(stroke
				(width 0.1524)
				(type default)
			)
			(layer "B.SilkS")
		)
		(fp_line
			(start 0.7874 -0.4064)
			(end -0.7874 -0.4064)
			(stroke
				(width 0.1524)
				(type default)
			)
			(layer "B.SilkS")
		)
		(fp_line
			(start -0.67945 0.3048)
			(end -0.120396 0.3048)
			(stroke
				(width 0.1)
				(type default)
			)
			(layer "B.Fab")
		)
		(fp_line
			(start -0.120396 0.3048)
			(end -0.120396 0.2794)
			(stroke
				(width 0.1)
				(type default)
			)
			(layer "B.Fab")
		)
		(fp_line
			(start 0.12065 0.3048)
			(end 0.67945 0.3048)
			(stroke
				(width 0.1)
				(type default)
			)
			(layer "B.Fab")
		)
		(fp_line
			(start 0.67945 0.3048)
			(end 0.67945 -0.305054)
			(stroke
				(width 0.1)
				(type default)
			)
			(layer "B.Fab")
		)
		(fp_line
			(start -0.120396 0.2794)
			(end 0.12065 0.2794)
			(stroke
				(width 0.1)
				(type default)
			)
			(layer "B.Fab")
		)
		(fp_line
			(start 0.12065 0.2794)
			(end 0.12065 0.3048)
			(stroke
				(width 0.1)
				(type default)
			)
			(layer "B.Fab")
		)
		(fp_line
			(start -0.12065 -0.2794)
			(end -0.12065 -0.3048)
			(stroke
				(width 0.1)
				(type default)
			)
			(layer "B.Fab")
		)
		(fp_line
			(start 0.12065 -0.2794)
			(end -0.12065 -0.2794)
			(stroke
				(width 0.1)
				(type default)
			)
			(layer "B.Fab")
		)
		(fp_line
			(start -0.67945 -0.3048)
			(end -0.67945 0.3048)
			(stroke
				(width 0.1)
				(type default)
			)
			(layer "B.Fab")
		)
		(fp_line
			(start -0.12065 -0.3048)
			(end -0.67945 -0.3048)
			(stroke
				(width 0.1)
				(type default)
			)
			(layer "B.Fab")
		)
		(fp_line
			(start 0.12065 -0.305054)
			(end 0.12065 -0.2794)
			(stroke
				(width 0.1)
				(type default)
			)
			(layer "B.Fab")
		)
		(fp_line
			(start 0.67945 -0.305054)
			(end 0.12065 -0.305054)
			(stroke
				(width 0.1)
				(type default)
			)
			(layer "B.Fab")
		)
		(pad "1" smd circle
			(at 0.40005 0 90)
			(size 0 0)
			(layers "B.Cu" "B.Mask" "B.Paste")
			(net "VFG3P3_CLK_GEN")
		)
		(pad "2" smd circle
			(at -0.40005 0 90)
			(size 0 0)
			(layers "B.Cu" "B.Mask" "B.Paste")
			(net "GND")
		)
	)
	(footprint ""
		(layer "B.Cu")
		(at 8.153146 -319.268856 180)
		(property "Reference" "C68"
			(at 0 0 0)
			(layer "B.SilkS")
			(hide yes)
			(effects
				(font
					(size 1.27 1.27)
				)
				(justify mirror)
			)
		)
		(property "Value" ""
			(at 0 0 0)
			(layer "B.Fab")
			(effects
				(font
					(size 1.27 1.27)
				)
				(justify mirror)
			)
		)
		(duplicate_pad_numbers_are_jumpers no)
		(fp_line
			(start 0.7874 0.4064)
			(end 0.7874 -0.4064)
			(stroke
				(width 0.1524)
				(type default)
			)
			(layer "B.SilkS")
		)
		(fp_line
			(start 0.7874 -0.4064)
			(end -0.7874 -0.4064)
			(stroke
				(width 0.1524)
				(type default)
			)
			(layer "B.SilkS")
		)
		(fp_line
			(start -0.7874 0.4064)
			(end 0.7874 0.4064)
			(stroke
				(width 0.1524)
				(type default)
			)
			(layer "B.SilkS")
		)
		(fp_line
			(start -0.7874 -0.4064)
			(end -0.7874 0.4064)
			(stroke
				(width 0.1524)
				(type default)
			)
			(layer "B.SilkS")
		)
		(fp_line
			(start 0.67945 0.3048)
			(end 0.67945 -0.305054)
			(stroke
				(width 0.1)
				(type default)
			)
			(layer "B.Fab")
		)
		(fp_line
			(start 0.67945 -0.305054)
			(end 0.12065 -0.305054)
			(stroke
				(width 0.1)
				(type default)
			)
			(layer "B.Fab")
		)
		(fp_line
			(start 0.12065 0.3048)
			(end 0.67945 0.3048)
			(stroke
				(width 0.1)
				(type default)
			)
			(layer "B.Fab")
		)
		(fp_line
			(start 0.12065 0.2794)
			(end 0.12065 0.3048)
			(stroke
				(width 0.1)
				(type default)
			)
			(layer "B.Fab")
		)
		(fp_line
			(start 0.12065 -0.2794)
			(end -0.12065 -0.2794)
			(stroke
				(width 0.1)
				(type default)
			)
			(layer "B.Fab")
		)
		(fp_line
			(start 0.12065 -0.305054)
			(end 0.12065 -0.2794)
			(stroke
				(width 0.1)
				(type default)
			)
			(layer "B.Fab")
		)
		(fp_line
			(start -0.120396 0.3048)
			(end -0.120396 0.2794)
			(stroke
				(width 0.1)
				(type default)
			)
			(layer "B.Fab")
		)
		(fp_line
			(start -0.120396 0.2794)
			(end 0.12065 0.2794)
			(stroke
				(width 0.1)
				(type default)
			)
			(layer "B.Fab")
		)
		(fp_line
			(start -0.12065 -0.2794)
			(end -0.12065 -0.3048)
			(stroke
				(width 0.1)
				(type default)
			)
			(layer "B.Fab")
		)
		(fp_line
			(start -0.12065 -0.3048)
			(end -0.67945 -0.3048)
			(stroke
				(width 0.1)
				(type default)
			)
			(layer "B.Fab")
		)
		(fp_line
			(start -0.67945 0.3048)
			(end -0.120396 0.3048)
			(stroke
				(width 0.1)
				(type default)
			)
			(layer "B.Fab")
		)
		(fp_line
			(start -0.67945 -0.3048)
			(end -0.67945 0.3048)
			(stroke
				(width 0.1)
				(type default)
			)
			(layer "B.Fab")
		)
		(pad "1" smd circle
			(at 0.40005 0)
			(size 0 0)
			(layers "B.Cu" "B.Mask" "B.Paste")
			(net "P3V3_AUX")
		)
		(pad "2" smd circle
			(at -0.40005 0)
			(size 0 0)
			(layers "B.Cu" "B.Mask" "B.Paste")
			(net "GND")
		)
	)
	(footprint ""
		(layer "B.Cu")
		(at 312.592974 -317.06566 90)
		(property "Reference" "R2490"
			(at 0 0 90)
			(layer "B.SilkS")
			(hide yes)
			(effects
				(font
					(size 1.27 1.27)
				)
				(justify mirror)
			)
		)
		(property "Value" ""
			(at 0 0 90)
			(layer "B.Fab")
			(effects
				(font
					(size 1.27 1.27)
				)
				(justify mirror)
			)
		)
		(duplicate_pad_numbers_are_jumpers no)
		(fp_line
			(start 0.7874 -0.4064)
			(end -0.7874 -0.4064)
			(stroke
				(width 0.1524)
				(type default)
			)
			(layer "B.SilkS")
		)
		(fp_line
			(start -0.7874 -0.4064)
			(end -0.7874 0.4064)
			(stroke
				(width 0.1524)
				(type default)
			)
			(layer "B.SilkS")
		)
		(fp_line
			(start 0.7874 0.4064)
			(end 0.7874 -0.4064)
			(stroke
				(width 0.1524)
				(type default)
			)
			(layer "B.SilkS")
		)
		(fp_line
			(start -0.7874 0.4064)
			(end 0.7874 0.4064)
			(stroke
				(width 0.1524)
				(type default)
			)
			(layer "B.SilkS")
		)
		(fp_line
			(start 0.67945 -0.305054)
			(end 0.12065 -0.305054)
			(stroke
				(width 0.1)
				(type default)
			)
			(layer "B.Fab")
		)
		(fp_line
			(start 0.12065 -0.305054)
			(end 0.12065 -0.2794)
			(stroke
				(width 0.1)
				(type default)
			)
			(layer "B.Fab")
		)
		(fp_line
			(start -0.12065 -0.3048)
			(end -0.67945 -0.3048)
			(stroke
				(width 0.1)
				(type default)
			)
			(layer "B.Fab")
		)
		(fp_line
			(start -0.67945 -0.3048)
			(end -0.67945 0.3048)
			(stroke
				(width 0.1)
				(type default)
			)
			(layer "B.Fab")
		)
		(fp_line
			(start 0.12065 -0.2794)
			(end -0.12065 -0.2794)
			(stroke
				(width 0.1)
				(type default)
			)
			(layer "B.Fab")
		)
		(fp_line
			(start -0.12065 -0.2794)
			(end -0.12065 -0.3048)
			(stroke
				(width 0.1)
				(type default)
			)
			(layer "B.Fab")
		)
		(fp_line
			(start 0.12065 0.2794)
			(end 0.12065 0.3048)
			(stroke
				(width 0.1)
				(type default)
			)
			(layer "B.Fab")
		)
		(fp_line
			(start -0.120396 0.2794)
			(end 0.12065 0.2794)
			(stroke
				(width 0.1)
				(type default)
			)
			(layer "B.Fab")
		)
		(fp_line
			(start 0.67945 0.3048)
			(end 0.67945 -0.305054)
			(stroke
				(width 0.1)
				(type default)
			)
			(layer "B.Fab")
		)
		(fp_line
			(start 0.12065 0.3048)
			(end 0.67945 0.3048)
			(stroke
				(width 0.1)
				(type default)
			)
			(layer "B.Fab")
		)
		(fp_line
			(start -0.120396 0.3048)
			(end -0.120396 0.2794)
			(stroke
				(width 0.1)
				(type default)
			)
			(layer "B.Fab")
		)
		(fp_line
			(start -0.67945 0.3048)
			(end -0.120396 0.3048)
			(stroke
				(width 0.1)
				(type default)
			)
			(layer "B.Fab")
		)
		(pad "1" smd circle
			(at 0.40005 0 270)
			(size 0 0)
			(layers "B.Cu" "B.Mask" "B.Paste")
			(net "PWRGD_FAIL_CPU0_AB")
		)
		(pad "2" smd circle
			(at -0.40005 0 270)
			(size 0 0)
			(layers "B.Cu" "B.Mask" "B.Paste")
			(net "PWRGD_FAIL_CPU0_AB_R1")
		)
	)
	(footprint ""
		(layer "B.Cu")
		(at 125.052836 -25.774142 180)
		(property "Reference" "C1097"
			(at 0 0 0)
			(layer "B.SilkS")
			(hide yes)
			(effects
				(font
					(size 1.27 1.27)
				)
				(justify mirror)
			)
		)
		(property "Value" ""
			(at 0 0 0)
			(layer "B.Fab")
			(effects
				(font
					(size 1.27 1.27)
				)
				(justify mirror)
			)
		)
		(duplicate_pad_numbers_are_jumpers no)
		(fp_line
			(start 0.299974 0.150114)
			(end 0.299974 -0.150114)
			(stroke
				(width 0.1)
				(type default)
			)
			(layer "B.Fab")
		)
		(fp_line
			(start 0.299974 -0.150114)
			(end -0.299974 -0.150114)
			(stroke
				(width 0.1)
				(type default)
			)
			(layer "B.Fab")
		)
		(fp_line
			(start -0.299974 0.150114)
			(end 0.299974 0.150114)
			(stroke
				(width 0.1)
				(type default)
			)
			(layer "B.Fab")
		)
		(fp_line
			(start -0.299974 -0.150114)
			(end -0.299974 0.150114)
			(stroke
				(width 0.1)
				(type default)
			)
			(layer "B.Fab")
		)
		(pad "1" smd rect
			(at 0.2667 0)
			(size 0.3048 0.381)
			(layers "B.Cu" "B.Mask" "B.Paste")
			(net "USB3_PCH_TX_DN<4>")
		)
		(pad "2" smd rect
			(at -0.2667 0)
			(size 0.3048 0.381)
			(layers "B.Cu" "B.Mask" "B.Paste")
			(net "USB3_PCH_TX_C_DN<4>")
		)
	)
	(footprint ""
		(layer "B.Cu")
		(at 420.698422 -132.632704)
		(property "Reference" "PR130"
			(at 0 0 0)
			(layer "B.SilkS")
			(hide yes)
			(effects
				(font
					(size 1.27 1.27)
				)
				(justify mirror)
			)
		)
		(property "Value" ""
			(at 0 0 0)
			(layer "B.Fab")
			(effects
				(font
					(size 1.27 1.27)
				)
				(justify mirror)
			)
		)
		(duplicate_pad_numbers_are_jumpers no)
		(fp_line
			(start -0.7874 -0.4064)
			(end -0.7874 0.4064)
			(stroke
				(width 0.1524)
				(type default)
			)
			(layer "B.SilkS")
		)
		(fp_line
			(start -0.7874 0.4064)
			(end 0.7874 0.4064)
			(stroke
				(width 0.1524)
				(type default)
			)
			(layer "B.SilkS")
		)
		(fp_line
			(start 0.7874 -0.4064)
			(end -0.7874 -0.4064)
			(stroke
				(width 0.1524)
				(type default)
			)
			(layer "B.SilkS")
		)
		(fp_line
			(start 0.7874 0.4064)
			(end 0.7874 -0.4064)
			(stroke
				(width 0.1524)
				(type default)
			)
			(layer "B.SilkS")
		)
		(fp_line
			(start -0.67945 -0.3048)
			(end -0.67945 0.3048)
			(stroke
				(width 0.1)
				(type default)
			)
			(layer "B.Fab")
		)
		(fp_line
			(start -0.67945 0.3048)
			(end -0.120396 0.3048)
			(stroke
				(width 0.1)
				(type default)
			)
			(layer "B.Fab")
		)
		(fp_line
			(start -0.12065 -0.3048)
			(end -0.67945 -0.3048)
			(stroke
				(width 0.1)
				(type default)
			)
			(layer "B.Fab")
		)
		(fp_line
			(start -0.12065 -0.2794)
			(end -0.12065 -0.3048)
			(stroke
				(width 0.1)
				(type default)
			)
			(layer "B.Fab")
		)
		(fp_line
			(start -0.120396 0.2794)
			(end 0.12065 0.2794)
			(stroke
				(width 0.1)
				(type default)
			)
			(layer "B.Fab")
		)
		(fp_line
			(start -0.120396 0.3048)
			(end -0.120396 0.2794)
			(stroke
				(width 0.1)
				(type default)
			)
			(layer "B.Fab")
		)
		(fp_line
			(start 0.12065 -0.305054)
			(end 0.12065 -0.2794)
			(stroke
				(width 0.1)
				(type default)
			)
			(layer "B.Fab")
		)
		(fp_line
			(start 0.12065 -0.2794)
			(end -0.12065 -0.2794)
			(stroke
				(width 0.1)
				(type default)
			)
			(layer "B.Fab")
		)
		(fp_line
			(start 0.12065 0.2794)
			(end 0.12065 0.3048)
			(stroke
				(width 0.1)
				(type default)
			)
			(layer "B.Fab")
		)
		(fp_line
			(start 0.12065 0.3048)
			(end 0.67945 0.3048)
			(stroke
				(width 0.1)
				(type default)
			)
			(layer "B.Fab")
		)
		(fp_line
			(start 0.67945 -0.305054)
			(end 0.12065 -0.305054)
			(stroke
				(width 0.1)
				(type default)
			)
			(layer "B.Fab")
		)
		(fp_line
			(start 0.67945 0.3048)
			(end 0.67945 -0.305054)
			(stroke
				(width 0.1)
				(type default)
			)
			(layer "B.Fab")
		)
		(pad "1" smd circle
			(at 0.40005 0 180)
			(size 0 0)
			(layers "B.Cu" "B.Mask" "B.Paste")
			(net "PVCCINFAON_CPU0_VCC")
		)
		(pad "2" smd circle
			(at -0.40005 0 180)
			(size 0 0)
			(layers "B.Cu" "B.Mask" "B.Paste")
			(net "P3V3_AUX")
		)
	)
	(footprint ""
		(layer "B.Cu")
		(at 49.682908 -193.25971 -90)
		(property "Reference" "R259"
			(at 0 0 90)
			(layer "B.SilkS")
			(hide yes)
			(effects
				(font
					(size 1.27 1.27)
				)
				(justify mirror)
			)
		)
		(property "Value" ""
			(at 0 0 90)
			(layer "B.Fab")
			(effects
				(font
					(size 1.27 1.27)
				)
				(justify mirror)
			)
		)
		(duplicate_pad_numbers_are_jumpers no)
		(fp_line
			(start -0.7874 0.4064)
			(end 0.7874 0.4064)
			(stroke
				(width 0.1524)
				(type default)
			)
			(layer "B.SilkS")
		)
		(fp_line
			(start 0.7874 0.4064)
			(end 0.7874 -0.4064)
			(stroke
				(width 0.1524)
				(type default)
			)
			(layer "B.SilkS")
		)
		(fp_line
			(start -0.7874 -0.4064)
			(end -0.7874 0.4064)
			(stroke
				(width 0.1524)
				(type default)
			)
			(layer "B.SilkS")
		)
		(fp_line
			(start 0.7874 -0.4064)
			(end -0.7874 -0.4064)
			(stroke
				(width 0.1524)
				(type default)
			)
			(layer "B.SilkS")
		)
		(fp_line
			(start -0.67945 0.3048)
			(end -0.120396 0.3048)
			(stroke
				(width 0.1)
				(type default)
			)
			(layer "B.Fab")
		)
		(fp_line
			(start -0.120396 0.3048)
			(end -0.120396 0.2794)
			(stroke
				(width 0.1)
				(type default)
			)
			(layer "B.Fab")
		)
		(fp_line
			(start 0.12065 0.3048)
			(end 0.67945 0.3048)
			(stroke
				(width 0.1)
				(type default)
			)
			(layer "B.Fab")
		)
		(fp_line
			(start 0.67945 0.3048)
			(end 0.67945 -0.305054)
			(stroke
				(width 0.1)
				(type default)
			)
			(layer "B.Fab")
		)
		(fp_line
			(start -0.120396 0.2794)
			(end 0.12065 0.2794)
			(stroke
				(width 0.1)
				(type default)
			)
			(layer "B.Fab")
		)
		(fp_line
			(start 0.12065 0.2794)
			(end 0.12065 0.3048)
			(stroke
				(width 0.1)
				(type default)
			)
			(layer "B.Fab")
		)
		(fp_line
			(start -0.12065 -0.2794)
			(end -0.12065 -0.3048)
			(stroke
				(width 0.1)
				(type default)
			)
			(layer "B.Fab")
		)
		(fp_line
			(start 0.12065 -0.2794)
			(end -0.12065 -0.2794)
			(stroke
				(width 0.1)
				(type default)
			)
			(layer "B.Fab")
		)
		(fp_line
			(start -0.67945 -0.3048)
			(end -0.67945 0.3048)
			(stroke
				(width 0.1)
				(type default)
			)
			(layer "B.Fab")
		)
		(fp_line
			(start -0.12065 -0.3048)
			(end -0.67945 -0.3048)
			(stroke
				(width 0.1)
				(type default)
			)
			(layer "B.Fab")
		)
		(fp_line
			(start 0.12065 -0.305054)
			(end 0.12065 -0.2794)
			(stroke
				(width 0.1)
				(type default)
			)
			(layer "B.Fab")
		)
		(fp_line
			(start 0.67945 -0.305054)
			(end 0.12065 -0.305054)
			(stroke
				(width 0.1)
				(type default)
			)
			(layer "B.Fab")
		)
		(pad "1" smd circle
			(at 0.40005 0 90)
			(size 0 0)
			(layers "B.Cu" "B.Mask" "B.Paste")
			(net "PVNN_TERM_CPU1")
		)
		(pad "2" smd circle
			(at -0.40005 0 90)
			(size 0 0)
			(layers "B.Cu" "B.Mask" "B.Paste")
			(net "FM_S3M_CPU1_LVC1_GPIO_2")
		)
	)
)
